(kicad_pcb
	(version 20260206)
	(generator "pcbnew")
	(generator_version "10.0")
	(general
		(thickness 1.6)
		(legacy_teardrops no)
	)
	(paper "A4")
	(title_block
		(title "03242023_DA0F0TMBIJ0_F0T_Motherboard_J_brd_V01_OCP.brd")
		(comment 1 "Grand Teton / footprints 4434-4439 of 6105")
	)
	(layers
		(0 "F.Cu" signal "TOP")
		(4 "In1.Cu" signal "GND")
		(6 "In2.Cu" signal "IN1")
		(8 "In3.Cu" signal "GND1")
		(10 "In4.Cu" signal "IN2")
		(12 "In5.Cu" signal "GND2")
		(14 "In6.Cu" signal "IN3")
		(16 "In7.Cu" signal "GND3")
		(18 "In8.Cu" signal "VCC")
		(20 "In9.Cu" signal "VCC1")
		(22 "In10.Cu" signal "GND4")
		(24 "In11.Cu" signal "IN4")
		(26 "In12.Cu" signal "GND5")
		(28 "In13.Cu" signal "IN5")
		(30 "In14.Cu" signal "GND6")
		(32 "In15.Cu" signal "IN6")
		(34 "In16.Cu" signal "GND7")
		(2 "B.Cu" signal "BOTTOM")
		(9 "F.Adhes" user "F.Adhesive")
		(11 "B.Adhes" user "B.Adhesive")
		(13 "F.Paste" user "Package Geometry/Pastemask Top")
		(15 "B.Paste" user "Package Geometry/Pastemask Bottom")
		(5 "F.SilkS" user "Ref Des/Silkscreen Top")
		(7 "B.SilkS" user "Ref Des/Silkscreen Bottom")
		(1 "F.Mask" user "Board Geometry/Soldermask Top")
		(3 "B.Mask" user "Board Geometry/Soldermask Bottom")
		(17 "Dwgs.User" user "User.Drawings")
		(19 "Cmts.User" user "User.Comments")
		(21 "Eco1.User" user "User.Eco1")
		(23 "Eco2.User" user "User.Eco2")
		(25 "Edge.Cuts" user "Board Geometry/Outline")
		(27 "Margin" user)
		(31 "F.CrtYd" user "Package Geometry/Place Bound Top")
		(29 "B.CrtYd" user "Package Geometry/Place Bound Bottom")
		(35 "F.Fab" user "Ref Des/Assembly Top")
		(33 "B.Fab" user "Ref Des/Assembly Bottom")
	)
	(footprint ""
		(layer "B.Cu")
		(at 258.50088 -78.577948 90)
		(property "Reference" "PR1647"
			(at 0 0 90)
			(layer "B.SilkS")
			(hide yes)
			(effects
				(font
					(size 1.27 1.27)
				)
				(justify mirror)
			)
		)
		(property "Value" ""
			(at 0 0 90)
			(layer "B.Fab")
			(effects
				(font
					(size 1.27 1.27)
				)
				(justify mirror)
			)
		)
		(duplicate_pad_numbers_are_jumpers no)
		(fp_line
			(start 0.7874 -0.4064)
			(end -0.7874 -0.4064)
			(stroke
				(width 0.1524)
				(type default)
			)
			(layer "B.SilkS")
		)
		(fp_line
			(start -0.7874 -0.4064)
			(end -0.7874 0.4064)
			(stroke
				(width 0.1524)
				(type default)
			)
			(layer "B.SilkS")
		)
		(fp_line
			(start 0.7874 0.4064)
			(end 0.7874 -0.4064)
			(stroke
				(width 0.1524)
				(type default)
			)
			(layer "B.SilkS")
		)
		(fp_line
			(start -0.7874 0.4064)
			(end 0.7874 0.4064)
			(stroke
				(width 0.1524)
				(type default)
			)
			(layer "B.SilkS")
		)
		(fp_line
			(start 0.67945 -0.305054)
			(end 0.12065 -0.305054)
			(stroke
				(width 0.1)
				(type default)
			)
			(layer "B.Fab")
		)
		(fp_line
			(start 0.12065 -0.305054)
			(end 0.12065 -0.2794)
			(stroke
				(width 0.1)
				(type default)
			)
			(layer "B.Fab")
		)
		(fp_line
			(start -0.12065 -0.3048)
			(end -0.67945 -0.3048)
			(stroke
				(width 0.1)
				(type default)
			)
			(layer "B.Fab")
		)
		(fp_line
			(start -0.67945 -0.3048)
			(end -0.67945 0.3048)
			(stroke
				(width 0.1)
				(type default)
			)
			(layer "B.Fab")
		)
		(fp_line
			(start 0.12065 -0.2794)
			(end -0.12065 -0.2794)
			(stroke
				(width 0.1)
				(type default)
			)
			(layer "B.Fab")
		)
		(fp_line
			(start -0.12065 -0.2794)
			(end -0.12065 -0.3048)
			(stroke
				(width 0.1)
				(type default)
			)
			(layer "B.Fab")
		)
		(fp_line
			(start 0.12065 0.2794)
			(end 0.12065 0.3048)
			(stroke
				(width 0.1)
				(type default)
			)
			(layer "B.Fab")
		)
		(fp_line
			(start -0.120396 0.2794)
			(end 0.12065 0.2794)
			(stroke
				(width 0.1)
				(type default)
			)
			(layer "B.Fab")
		)
		(fp_line
			(start 0.67945 0.3048)
			(end 0.67945 -0.305054)
			(stroke
				(width 0.1)
				(type default)
			)
			(layer "B.Fab")
		)
		(fp_line
			(start 0.12065 0.3048)
			(end 0.67945 0.3048)
			(stroke
				(width 0.1)
				(type default)
			)
			(layer "B.Fab")
		)
		(fp_line
			(start -0.120396 0.3048)
			(end -0.120396 0.2794)
			(stroke
				(width 0.1)
				(type default)
			)
			(layer "B.Fab")
		)
		(fp_line
			(start -0.67945 0.3048)
			(end -0.120396 0.3048)
			(stroke
				(width 0.1)
				(type default)
			)
			(layer "B.Fab")
		)
		(pad "1" smd circle
			(at 0.40005 0 270)
			(size 0 0)
			(layers "B.Cu" "B.Mask" "B.Paste")
			(net "P3V3_AUX")
		)
		(pad "2" smd circle
			(at -0.40005 0 270)
			(size 0 0)
			(layers "B.Cu" "B.Mask" "B.Paste")
			(net "FM_P1V05_PCH_AUX_R_EN")
		)
	)
	(footprint ""
		(layer "B.Cu")
		(at 72.401684 -188.458856 90)
		(property "Reference" "R60"
			(at 0 0 90)
			(layer "B.SilkS")
			(hide yes)
			(effects
				(font
					(size 1.27 1.27)
				)
				(justify mirror)
			)
		)
		(property "Value" ""
			(at 0 0 90)
			(layer "B.Fab")
			(effects
				(font
					(size 1.27 1.27)
				)
				(justify mirror)
			)
		)
		(duplicate_pad_numbers_are_jumpers no)
		(fp_line
			(start 0.7874 -0.4064)
			(end -0.7874 -0.4064)
			(stroke
				(width 0.1524)
				(type default)
			)
			(layer "B.SilkS")
		)
		(fp_line
			(start -0.7874 -0.4064)
			(end -0.7874 0.4064)
			(stroke
				(width 0.1524)
				(type default)
			)
			(layer "B.SilkS")
		)
		(fp_line
			(start 0.7874 0.4064)
			(end 0.7874 -0.4064)
			(stroke
				(width 0.1524)
				(type default)
			)
			(layer "B.SilkS")
		)
		(fp_line
			(start -0.7874 0.4064)
			(end 0.7874 0.4064)
			(stroke
				(width 0.1524)
				(type default)
			)
			(layer "B.SilkS")
		)
		(fp_line
			(start 0.67945 -0.305054)
			(end 0.12065 -0.305054)
			(stroke
				(width 0.1)
				(type default)
			)
			(layer "B.Fab")
		)
		(fp_line
			(start 0.12065 -0.305054)
			(end 0.12065 -0.2794)
			(stroke
				(width 0.1)
				(type default)
			)
			(layer "B.Fab")
		)
		(fp_line
			(start -0.12065 -0.3048)
			(end -0.67945 -0.3048)
			(stroke
				(width 0.1)
				(type default)
			)
			(layer "B.Fab")
		)
		(fp_line
			(start -0.67945 -0.3048)
			(end -0.67945 0.3048)
			(stroke
				(width 0.1)
				(type default)
			)
			(layer "B.Fab")
		)
		(fp_line
			(start 0.12065 -0.2794)
			(end -0.12065 -0.2794)
			(stroke
				(width 0.1)
				(type default)
			)
			(layer "B.Fab")
		)
		(fp_line
			(start -0.12065 -0.2794)
			(end -0.12065 -0.3048)
			(stroke
				(width 0.1)
				(type default)
			)
			(layer "B.Fab")
		)
		(fp_line
			(start 0.12065 0.2794)
			(end 0.12065 0.3048)
			(stroke
				(width 0.1)
				(type default)
			)
			(layer "B.Fab")
		)
		(fp_line
			(start -0.120396 0.2794)
			(end 0.12065 0.2794)
			(stroke
				(width 0.1)
				(type default)
			)
			(layer "B.Fab")
		)
		(fp_line
			(start 0.67945 0.3048)
			(end 0.67945 -0.305054)
			(stroke
				(width 0.1)
				(type default)
			)
			(layer "B.Fab")
		)
		(fp_line
			(start 0.12065 0.3048)
			(end 0.67945 0.3048)
			(stroke
				(width 0.1)
				(type default)
			)
			(layer "B.Fab")
		)
		(fp_line
			(start -0.120396 0.3048)
			(end -0.120396 0.2794)
			(stroke
				(width 0.1)
				(type default)
			)
			(layer "B.Fab")
		)
		(fp_line
			(start -0.67945 0.3048)
			(end -0.120396 0.3048)
			(stroke
				(width 0.1)
				(type default)
			)
			(layer "B.Fab")
		)
		(pad "1" smd circle
			(at 0.40005 0 270)
			(size 0 0)
			(layers "B.Cu" "B.Mask" "B.Paste")
			(net "SVID_ALERT1_CPU1_N")
		)
		(pad "2" smd circle
			(at -0.40005 0 270)
			(size 0 0)
			(layers "B.Cu" "B.Mask" "B.Paste")
			(net "SVID_ALERT1_CPU1_R_N")
		)
	)
	(footprint ""
		(layer "B.Cu")
		(at 359.960418 -296.054526)
		(property "Reference" "C392"
			(at 0 0 0)
			(layer "B.SilkS")
			(hide yes)
			(effects
				(font
					(size 1.27 1.27)
				)
				(justify mirror)
			)
		)
		(property "Value" ""
			(at 0 0 0)
			(layer "B.Fab")
			(effects
				(font
					(size 1.27 1.27)
				)
				(justify mirror)
			)
		)
		(duplicate_pad_numbers_are_jumpers no)
		(fp_line
			(start -1.524 -0.762)
			(end -1.524 0.762)
			(stroke
				(width 0.1524)
				(type default)
			)
			(layer "B.SilkS")
		)
		(fp_line
			(start -1.524 0.762)
			(end 1.524 0.762)
			(stroke
				(width 0.1524)
				(type default)
			)
			(layer "B.SilkS")
		)
		(fp_line
			(start 1.524 -0.762)
			(end -1.524 -0.762)
			(stroke
				(width 0.1524)
				(type default)
			)
			(layer "B.SilkS")
		)
		(fp_line
			(start 1.524 0.762)
			(end 1.524 -0.762)
			(stroke
				(width 0.1524)
				(type default)
			)
			(layer "B.SilkS")
		)
		(fp_line
			(start -1.1049 -0.724916)
			(end 1.1049 -0.724916)
			(stroke
				(width 0.1)
				(type default)
			)
			(layer "B.Fab")
		)
		(fp_line
			(start -1.1049 0.724916)
			(end -1.1049 -0.724916)
			(stroke
				(width 0.1)
				(type default)
			)
			(layer "B.Fab")
		)
		(fp_line
			(start 1.1049 -0.724916)
			(end 1.1049 0.724916)
			(stroke
				(width 0.1)
				(type default)
			)
			(layer "B.Fab")
		)
		(fp_line
			(start 1.1049 0.724916)
			(end -1.1049 0.724916)
			(stroke
				(width 0.1)
				(type default)
			)
			(layer "B.Fab")
		)
		(pad "1" smd rect
			(at 0.889 0)
			(size 1.016 1.27)
			(layers "B.Cu" "B.Mask" "B.Paste")
			(net "PVCCIN_CPU0")
		)
		(pad "2" smd rect
			(at -0.889 0)
			(size 1.016 1.27)
			(layers "B.Cu" "B.Mask" "B.Paste")
			(net "GND")
		)
	)
	(footprint ""
		(layer "B.Cu")
		(at 310.567578 -193.52895 -90)
		(property "Reference" "R3"
			(at 0 0 90)
			(layer "B.SilkS")
			(hide yes)
			(effects
				(font
					(size 1.27 1.27)
				)
				(justify mirror)
			)
		)
		(property "Value" ""
			(at 0 0 90)
			(layer "B.Fab")
			(effects
				(font
					(size 1.27 1.27)
				)
				(justify mirror)
			)
		)
		(duplicate_pad_numbers_are_jumpers no)
		(fp_line
			(start -0.7874 0.4064)
			(end 0.7874 0.4064)
			(stroke
				(width 0.1524)
				(type default)
			)
			(layer "B.SilkS")
		)
		(fp_line
			(start 0.7874 0.4064)
			(end 0.7874 -0.4064)
			(stroke
				(width 0.1524)
				(type default)
			)
			(layer "B.SilkS")
		)
		(fp_line
			(start -0.7874 -0.4064)
			(end -0.7874 0.4064)
			(stroke
				(width 0.1524)
				(type default)
			)
			(layer "B.SilkS")
		)
		(fp_line
			(start 0.7874 -0.4064)
			(end -0.7874 -0.4064)
			(stroke
				(width 0.1524)
				(type default)
			)
			(layer "B.SilkS")
		)
		(fp_line
			(start -0.67945 0.3048)
			(end -0.120396 0.3048)
			(stroke
				(width 0.1)
				(type default)
			)
			(layer "B.Fab")
		)
		(fp_line
			(start -0.120396 0.3048)
			(end -0.120396 0.2794)
			(stroke
				(width 0.1)
				(type default)
			)
			(layer "B.Fab")
		)
		(fp_line
			(start 0.12065 0.3048)
			(end 0.67945 0.3048)
			(stroke
				(width 0.1)
				(type default)
			)
			(layer "B.Fab")
		)
		(fp_line
			(start 0.67945 0.3048)
			(end 0.67945 -0.305054)
			(stroke
				(width 0.1)
				(type default)
			)
			(layer "B.Fab")
		)
		(fp_line
			(start -0.120396 0.2794)
			(end 0.12065 0.2794)
			(stroke
				(width 0.1)
				(type default)
			)
			(layer "B.Fab")
		)
		(fp_line
			(start 0.12065 0.2794)
			(end 0.12065 0.3048)
			(stroke
				(width 0.1)
				(type default)
			)
			(layer "B.Fab")
		)
		(fp_line
			(start -0.12065 -0.2794)
			(end -0.12065 -0.3048)
			(stroke
				(width 0.1)
				(type default)
			)
			(layer "B.Fab")
		)
		(fp_line
			(start 0.12065 -0.2794)
			(end -0.12065 -0.2794)
			(stroke
				(width 0.1)
				(type default)
			)
			(layer "B.Fab")
		)
		(fp_line
			(start -0.67945 -0.3048)
			(end -0.67945 0.3048)
			(stroke
				(width 0.1)
				(type default)
			)
			(layer "B.Fab")
		)
		(fp_line
			(start -0.12065 -0.3048)
			(end -0.67945 -0.3048)
			(stroke
				(width 0.1)
				(type default)
			)
			(layer "B.Fab")
		)
		(fp_line
			(start 0.12065 -0.305054)
			(end 0.12065 -0.2794)
			(stroke
				(width 0.1)
				(type default)
			)
			(layer "B.Fab")
		)
		(fp_line
			(start 0.67945 -0.305054)
			(end 0.12065 -0.305054)
			(stroke
				(width 0.1)
				(type default)
			)
			(layer "B.Fab")
		)
		(pad "1" smd circle
			(at 0.40005 0 90)
			(size 0 0)
			(layers "B.Cu" "B.Mask" "B.Paste")
			(net "PECI_CPU_GTL")
		)
		(pad "2" smd circle
			(at -0.40005 0 90)
			(size 0 0)
			(layers "B.Cu" "B.Mask" "B.Paste")
			(net "PECI_CPU0_GTL_R")
		)
	)
	(footprint ""
		(layer "B.Cu")
		(at 332.197456 -58.473086 -90)
		(property "Reference" "C1181"
			(at 0 0 90)
			(layer "B.SilkS")
			(hide yes)
			(effects
				(font
					(size 1.27 1.27)
				)
				(justify mirror)
			)
		)
		(property "Value" ""
			(at 0 0 90)
			(layer "B.Fab")
			(effects
				(font
					(size 1.27 1.27)
				)
				(justify mirror)
			)
		)
		(duplicate_pad_numbers_are_jumpers no)
		(fp_line
			(start -1.2954 0.5842)
			(end 1.2954 0.5842)
			(stroke
				(width 0.1524)
				(type default)
			)
			(layer "B.SilkS")
		)
		(fp_line
			(start 1.2954 0.5842)
			(end 1.2954 -0.5842)
			(stroke
				(width 0.1524)
				(type default)
			)
			(layer "B.SilkS")
		)
		(fp_line
			(start -1.2954 -0.5842)
			(end -1.2954 0.5842)
			(stroke
				(width 0.1524)
				(type default)
			)
			(layer "B.SilkS")
		)
		(fp_line
			(start 0 -0.5842)
			(end 0 0.5842)
			(stroke
				(width 0.1524)
				(type default)
			)
			(layer "B.SilkS")
		)
		(fp_line
			(start 1.2954 -0.5842)
			(end -1.2954 -0.5842)
			(stroke
				(width 0.1524)
				(type default)
			)
			(layer "B.SilkS")
		)
		(fp_line
			(start -0.8636 0.4572)
			(end 0.8636 0.4572)
			(stroke
				(width 0.1)
				(type default)
			)
			(layer "B.Fab")
		)
		(fp_line
			(start 0.8636 0.4572)
			(end 0.8636 0.4064)
			(stroke
				(width 0.1)
				(type default)
			)
			(layer "B.Fab")
		)
		(fp_line
			(start -1.1938 0.4064)
			(end -0.8636 0.4064)
			(stroke
				(width 0.1)
				(type default)
			)
			(layer "B.Fab")
		)
		(fp_line
			(start -0.8636 0.4064)
			(end -0.8636 0.4572)
			(stroke
				(width 0.1)
				(type default)
			)
			(layer "B.Fab")
		)
		(fp_line
			(start 0.8636 0.4064)
			(end 1.1938 0.4064)
			(stroke
				(width 0.1)
				(type default)
			)
			(layer "B.Fab")
		)
		(fp_line
			(start 1.1938 0.4064)
			(end 1.1938 -0.4064)
			(stroke
				(width 0.1)
				(type default)
			)
			(layer "B.Fab")
		)
		(fp_line
			(start -1.1938 -0.4064)
			(end -1.1938 0.4064)
			(stroke
				(width 0.1)
				(type default)
			)
			(layer "B.Fab")
		)
		(fp_line
			(start -0.8636 -0.4064)
			(end -1.1938 -0.4064)
			(stroke
				(width 0.1)
				(type default)
			)
			(layer "B.Fab")
		)
		(fp_line
			(start 0.8636 -0.4064)
			(end 0.8636 -0.4572)
			(stroke
				(width 0.1)
				(type default)
			)
			(layer "B.Fab")
		)
		(fp_line
			(start 1.1938 -0.4064)
			(end 0.8636 -0.4064)
			(stroke
				(width 0.1)
				(type default)
			)
			(layer "B.Fab")
		)
		(fp_line
			(start -0.8636 -0.4572)
			(end -0.8636 -0.4064)
			(stroke
				(width 0.1)
				(type default)
			)
			(layer "B.Fab")
		)
		(fp_line
			(start 0.8636 -0.4572)
			(end -0.8636 -0.4572)
			(stroke
				(width 0.1)
				(type default)
			)
			(layer "B.Fab")
		)
		(pad "1" smd rect
			(at 0.7366 0 180)
			(size 0.7112 0.8128)
			(layers "B.Cu" "B.Mask" "B.Paste")
			(net "P1V8_PCH_AUX")
		)
		(pad "2" smd rect
			(at -0.7366 0 180)
			(size 0.7112 0.8128)
			(layers "B.Cu" "B.Mask" "B.Paste")
			(net "GND")
		)
	)
	(footprint ""
		(layer "B.Cu")
		(at 380.80823 -190.82131 90)
		(property "Reference" "R1240"
			(at 0 0 90)
			(layer "B.SilkS")
			(hide yes)
			(effects
				(font
					(size 1.27 1.27)
				)
				(justify mirror)
			)
		)
		(property "Value" ""
			(at 0 0 90)
			(layer "B.Fab")
			(effects
				(font
					(size 1.27 1.27)
				)
				(justify mirror)
			)
		)
		(duplicate_pad_numbers_are_jumpers no)
		(fp_line
			(start 0.7874 -0.4064)
			(end -0.7874 -0.4064)
			(stroke
				(width 0.1524)
				(type default)
			)
			(layer "B.SilkS")
		)
		(fp_line
			(start -0.7874 -0.4064)
			(end -0.7874 0.4064)
			(stroke
				(width 0.1524)
				(type default)
			)
			(layer "B.SilkS")
		)
		(fp_line
			(start 0.7874 0.4064)
			(end 0.7874 -0.4064)
			(stroke
				(width 0.1524)
				(type default)
			)
			(layer "B.SilkS")
		)
		(fp_line
			(start -0.7874 0.4064)
			(end 0.7874 0.4064)
			(stroke
				(width 0.1524)
				(type default)
			)
			(layer "B.SilkS")
		)
		(fp_line
			(start 0.67945 -0.305054)
			(end 0.12065 -0.305054)
			(stroke
				(width 0.1)
				(type default)
			)
			(layer "B.Fab")
		)
		(fp_line
			(start 0.12065 -0.305054)
			(end 0.12065 -0.2794)
			(stroke
				(width 0.1)
				(type default)
			)
			(layer "B.Fab")
		)
		(fp_line
			(start -0.12065 -0.3048)
			(end -0.67945 -0.3048)
			(stroke
				(width 0.1)
				(type default)
			)
			(layer "B.Fab")
		)
		(fp_line
			(start -0.67945 -0.3048)
			(end -0.67945 0.3048)
			(stroke
				(width 0.1)
				(type default)
			)
			(layer "B.Fab")
		)
		(fp_line
			(start 0.12065 -0.2794)
			(end -0.12065 -0.2794)
			(stroke
				(width 0.1)
				(type default)
			)
			(layer "B.Fab")
		)
		(fp_line
			(start -0.12065 -0.2794)
			(end -0.12065 -0.3048)
			(stroke
				(width 0.1)
				(type default)
			)
			(layer "B.Fab")
		)
		(fp_line
			(start 0.12065 0.2794)
			(end 0.12065 0.3048)
			(stroke
				(width 0.1)
				(type default)
			)
			(layer "B.Fab")
		)
		(fp_line
			(start -0.120396 0.2794)
			(end 0.12065 0.2794)
			(stroke
				(width 0.1)
				(type default)
			)
			(layer "B.Fab")
		)
		(fp_line
			(start 0.67945 0.3048)
			(end 0.67945 -0.305054)
			(stroke
				(width 0.1)
				(type default)
			)
			(layer "B.Fab")
		)
		(fp_line
			(start 0.12065 0.3048)
			(end 0.67945 0.3048)
			(stroke
				(width 0.1)
				(type default)
			)
			(layer "B.Fab")
		)
		(fp_line
			(start -0.120396 0.3048)
			(end -0.120396 0.2794)
			(stroke
				(width 0.1)
				(type default)
			)
			(layer "B.Fab")
		)
		(fp_line
			(start -0.67945 0.3048)
			(end -0.120396 0.3048)
			(stroke
				(width 0.1)
				(type default)
			)
			(layer "B.Fab")
		)
		(pad "1" smd circle
			(at 0.40005 0 270)
			(size 0 0)
			(layers "B.Cu" "B.Mask" "B.Paste")
			(net "H_CPU0_PM_FAST_WAKE_N")
		)
		(pad "2" smd circle
			(at -0.40005 0 270)
			(size 0 0)
			(layers "B.Cu" "B.Mask" "B.Paste")
			(net "H_CPU_PM_FAST_WAKE_N")
		)
	)
)
